# T6G (Grand Teton) — schematic netlist excerpt (pin names and nets, part order shuffled) for the footprints in the layout excerpt that follows; sources: Cadence DE-HDL packaged netlist, KiCad conversion of 04192023_DAF0TMB3IC0_F0TG_MB_C_brd_V02_OCP.brd

J26  SCONN288_DDR506112002KQ  IO  pkg DDR288S_1-1VXC  page 99
  VIN_BULK0  = P12V_MEM_CPU1
  RFU0  = NC
  VIN_MGMT  = P3V3_AUX
  HSCL  = I3C_SPD_DDRB_CPU1_SCL
  HSDA  = I3C_SPD_DDRB_CPU1_SDA
  VSS0  = GND
  DQ0_A  = M_B_CPU1_SA_DQ<0>
  VSS1  = GND
  DQ1_A  = M_B_CPU1_SA_DQ<1>
  VSS2  = GND
  DQS0_A_T  = M_B_CPU1_SA_DQS_DP<0>
  DQS0_A_C  = M_B_CPU1_SA_DQS_DN<0>
  VSS3  = GND
  DQ4_A  = M_B_CPU1_SA_DQ<4>
  VSS4  = GND
  DQ5_A  = M_B_CPU1_SA_DQ<5>
  VSS5  = GND
  DQ8_A  = M_B_CPU1_SA_DQ<8>
  VSS6  = GND
  DQ9_A  = M_B_CPU1_SA_DQ<9>
  VSS7  = GND
  DQS1_A_T  = M_B_CPU1_SA_DQS_DP<1>
  DQS1_A_C  = M_B_CPU1_SA_DQS_DN<1>
  VSS8  = GND
  DQ12_A  = M_B_CPU1_SA_DQ<12>
  VSS9  = GND
  DQ13_A  = M_B_CPU1_SA_DQ<13>
  VSS10  = GND
  DQ16_A  = M_B_CPU1_SA_DQ<16>
  VSS11  = GND
  DQ17_A  = M_B_CPU1_SA_DQ<17>
  VSS12  = GND
  DQS2_A_T  = M_B_CPU1_SA_DQS_DP<2>
  DQS2_A_C  = M_B_CPU1_SA_DQS_DN<2>
  VSS13  = GND
  DQ20_A  = M_B_CPU1_SA_DQ<20>
  VSS14  = GND
  DQ21_A  = M_B_CPU1_SA_DQ<21>
  VSS15  = GND
  DQ24_A  = M_B_CPU1_SA_DQ<24>
  VSS16  = GND
  DQ25_A  = M_B_CPU1_SA_DQ<25>
  VSS17  = GND
  DQS3_A_T  = M_B_CPU1_SA_DQS_DP<3>
  DQS3_A_C  = M_B_CPU1_SA_DQS_DN<3>
  VSS18  = GND
  DQ28_A  = M_B_CPU1_SA_DQ<28>
  VSS19  = GND
  DQ29_A  = M_B_CPU1_SA_DQ<29>
  VSS20  = GND
  CB0_A  = M_B_CPU1_SA_CB<0>
  VSS21  = GND
  CB1_A  = M_B_CPU1_SA_CB<1>
  VSS22  = GND
  DQS4_A_T  = M_B_CPU1_SA_DQS_DP<4>
  DQS4_A_C  = M_B_CPU1_SA_DQS_DN<4>
  VSS23  = GND
  CB4_A  = M_B_CPU1_SA_CB<4>
  VSS24  = GND
  CB5_A  = M_B_CPU1_SA_CB<5>
  VSS25  = GND
  ALERT_N  = M_B_CPU1_ALERT_N
  VSS26  = GND
  CS0_A_N  = M_B_CPU1_SA_CS_N<0>
  VSS27  = GND
  CA0_A  = M_B_CPU1_SA_CA<0>
  VSS28  = GND
  CA2_A  = M_B_CPU1_SA_CA<2>
  VSS29  = GND
  CA4_A  = M_B_CPU1_SA_CA<4>
  VSS30  = GND
  CA6_A  = M_B_CPU1_SA_CA<6>
  VSS31  = GND
  PAR_A  = M_B_CPU1_SA_PAR
  VSS32  = GND
  CA0_B  = M_B_CPU1_SB_CA<0>
  VSS33  = GND
  CA2_B  = M_B_CPU1_SB_CA<2>
  VSS34  = GND
  CA4_B  = M_B_CPU1_SB_CA<4>
  VSS35  = GND
  CA6_B  = M_B_CPU1_SB_CA<6>
  VSS36  = GND
  CS0_B_N  = M_B_CPU1_SB_CS_N<0>
  VSS37  = GND
  \lbd||rsp_a_n\  = M_B_CPU1_SA_RSP<0>
  \lbs||rsp_b_n\  = M_B_CPU1_SB_RSP<0>
  VSS38  = GND
  CB4_B  = M_B_CPU1_SB_CB<4>
  VSS39  = GND
  CB5_B  = M_B_CPU1_SB_CB<5>
  VSS40  = GND
  \dqs9_b_t||tdqs9_b_t||dbi4_b_n\  = M_B_CPU1_SB_DQS_DP<9>
  \dqs9_b_c||tdqs9_b_c\  = M_B_CPU1_SB_DQS_DN<9>
  VSS41  = GND
  CB0_B  = M_B_CPU1_SB_CB<0>
  VSS42  = GND
  CB1_B  = M_B_CPU1_SB_CB<1>
  VSS43  = GND
  DQ0_B  = M_B_CPU1_SB_DQ<0>
  VSS44  = GND
  DQ1_B  = M_B_CPU1_SB_DQ<1>
  VSS45  = GND
  DQS0_B_T  = M_B_CPU1_SB_DQS_DP<0>
  DQS0_B_C  = M_B_CPU1_SB_DQS_DN<0>
  VSS46  = GND
  DQ4_B  = M_B_CPU1_SB_DQ<4>
  VSS47  = GND
  DQ5_B  = M_B_CPU1_SB_DQ<5>
  VSS48  = GND
  DQ8_B  = M_B_CPU1_SB_DQ<8>
  VSS49  = GND
  DQ9_B  = M_B_CPU1_SB_DQ<9>
  VSS50  = GND
  DQS1_B_T  = M_B_CPU1_SB_DQS_DP<1>
  DQS1_B_C  = M_B_CPU1_SB_DQS_DN<1>
  VSS51  = GND
  DQ12_B  = M_B_CPU1_SB_DQ<12>
  VSS52  = GND
  DQ13_B  = M_B_CPU1_SB_DQ<13>
  VSS53  = GND
  DQ16_B  = M_B_CPU1_SB_DQ<16>
  VSS54  = GND
  DQ17_B  = M_B_CPU1_SB_DQ<17>
  VSS55  = GND
  DQS2_B_T  = M_B_CPU1_SB_DQS_DP<2>
  DQS2_B_C  = M_B_CPU1_SB_DQS_DN<2>
  VSS56  = GND
  DQ20_B  = M_B_CPU1_SB_DQ<20>
  VSS57  = GND
  DQ21_B  = M_B_CPU1_SB_DQ<21>
  VSS58  = GND
  DQ24_B  = M_B_CPU1_SB_DQ<24>
  VSS59  = GND
  DQ25_B  = M_B_CPU1_SB_DQ<25>
  VSS60  = GND
  DQS3_B_T  = M_B_CPU1_SB_DQS_DP<3>
  DQS3_B_C  = M_B_CPU1_SB_DQS_DN<3>
  VSS61  = GND
  DQ28_B  = M_B_CPU1_SB_DQ<28>
  VSS62  = GND
  DQ29_B  = M_B_CPU1_SB_DQ<29>
  VSS63  = GND
  RFU1  = NC
  VIN_BULK1  = P12V_MEM_CPU1
  VIN_BULK2  = P12V_MEM_CPU1
  \pwr_good||fail_n\  = PWRGD_CHB_CPU1_DIMM
  HAS  = PD_CHB_CPU1_DIMM_SAA
  RFU2  = NC
  RFU3  = NC
  VSS64  = GND
  DQ2_A  = M_B_CPU1_SA_DQ<2>
  VSS65  = GND
  DQ3_A  = M_B_CPU1_SA_DQ<3>
  VSS66  = GND
  \dqs5_a_c||tdqs5_a_c||dqs5_a_t||tdqs5_a_t\  = M_B_CPU1_SA_DQS_DN<5>
  \dqs5_a_t||tdqs5_a_t\  = M_B_CPU1_SA_DQS_DP<5>
  VSS67  = GND
  DQ6_A  = M_B_CPU1_SA_DQ<6>
  VSS68  = GND
  DQ7_A  = M_B_CPU1_SA_DQ<7>
  VSS69  = GND
  DQ10_A  = M_B_CPU1_SA_DQ<10>
  VSS70  = GND
  DQ11_A  = M_B_CPU1_SA_DQ<11>
  VSS71  = GND
  \dqs6_a_c||tdqs6_a_c||dqs6_a_t||tdqs6_a_t\  = M_B_CPU1_SA_DQS_DN<6>
  \dqs6_a_t||tdqs6_a_t\  = M_B_CPU1_SA_DQS_DP<6>
  VSS72  = GND
  DQ14_A  = M_B_CPU1_SA_DQ<14>
  VSS73  = GND
  DQ15_A  = M_B_CPU1_SA_DQ<15>
  VSS74  = GND
  DQ18_A  = M_B_CPU1_SA_DQ<18>
  VSS75  = GND
  DQ19_A  = M_B_CPU1_SA_DQ<19>
  VSS76  = GND
  \dqs7_a_c||tdqs7_a_c\  = M_B_CPU1_SA_DQS_DN<7>
  \dqs7_a_t||tdqs7_a_t\  = M_B_CPU1_SA_DQS_DP<7>
  VSS77  = GND
  DQ22_A  = M_B_CPU1_SA_DQ<22>
  VSS78  = GND
  DQ23_A  = M_B_CPU1_SA_DQ<23>
  VSS79  = GND
  DQ26_A  = M_B_CPU1_SA_DQ<26>
  VSS80  = GND
  DQ27_A  = M_B_CPU1_SA_DQ<27>
  VSS81  = GND
  \dqs8_a_c||tdqs8_a_c\  = M_B_CPU1_SA_DQS_DN<8>
  \dqs8_a_t||tdqs8_a_t\  = M_B_CPU1_SA_DQS_DP<8>
  VSS82  = GND
  DQ30_A  = M_B_CPU1_SA_DQ<30>
  VSS83  = GND
  DQ31_A  = M_B_CPU1_SA_DQ<31>
  VSS84  = GND
  CB2_A  = M_B_CPU1_SA_CB<2>
  VSS85  = GND
  CB3_A  = M_B_CPU1_SA_CB<3>
  VSS86  = GND
  \dqs9_a_c||tdqs9_a_c\  = M_B_CPU1_SA_DQS_DN<9>
  \dqs9_a_t||tdqs9_a_t\  = M_B_CPU1_SA_DQS_DP<9>
  VSS87  = GND
  CB6_A  = M_B_CPU1_SA_CB<6>
  VSS88  = GND
  CB7_A  = M_B_CPU1_SA_CB<7>
  VSS89  = GND
  RESET_N  = M_B_CPU1_RESET_N
  VSS90  = GND
  CS1_A_N  = M_B_CPU1_SA_CS_N<1>
  VSS91  = GND
  CA1_A  = M_B_CPU1_SA_CA<1>
  VSS92  = GND
  CA3_A  = M_B_CPU1_SA_CA<3>
  VSS93  = GND
  CA5_A  = M_B_CPU1_SA_CA<5>
  VSS94  = GND
  CK_T  = M_B_CPU1_CLK_DP<0>
  CK_C  = M_B_CPU1_CLK_DN<0>
  VSS95  = GND
  RFU4  = NC
  CA1_B  = M_B_CPU1_SB_CA<1>
  VSS96  = GND
  CA3_B  = M_B_CPU1_SB_CA<3>
  VSS97  = GND
  CA5_B  = M_B_CPU1_SB_CA<5>
  VSS98  = GND
  PAR_B  = M_B_CPU1_SB_PAR
  VSS99  = GND
  CS1_B_N  = M_B_CPU1_SB_CS_N<1>
  VSS100  = GND
  RFU5  = NC
  RFU6  = NC
  VSS101  = GND
  CB6_B  = M_B_CPU1_SB_CB<6>
  VSS102  = GND
  CB7_B  = M_B_CPU1_SB_CB<7>
  VSS103  = GND
  DQS4_B_C  = M_B_CPU1_SB_DQS_DN<4>
  DQS4_B_T  = M_B_CPU1_SB_DQS_DP<4>
  VSS104  = GND
  CB2_B  = M_B_CPU1_SB_CB<2>
  VSS105  = GND
  CB3_B  = M_B_CPU1_SB_CB<3>
  VSS106  = GND
  DQ2_B  = M_B_CPU1_SB_DQ<2>
  VSS107  = GND
  DQ3_B  = M_B_CPU1_SB_DQ<3>
  VSS108  = GND
  \dqs5_b_c||tdqs5_b_c\  = M_B_CPU1_SB_DQS_DN<5>
  \dqs5_b_t||tdqs5_b_t\  = M_B_CPU1_SB_DQS_DP<5>
  VSS109  = GND
  DQ6_B  = M_B_CPU1_SB_DQ<6>
  VSS110  = GND
  DQ7_B  = M_B_CPU1_SB_DQ<7>
  VSS111  = GND
  DQ10_B  = M_B_CPU1_SB_DQ<10>
  VSS112  = GND
  DQ11_B  = M_B_CPU1_SB_DQ<11>
  VSS113  = GND
  \dqs6_b_c||tdqs6_b_c\  = M_B_CPU1_SB_DQS_DN<6>
  \dqs6_b_t||tdqs6_b_t\  = M_B_CPU1_SB_DQS_DP<6>
  VSS114  = GND
  DQ14_B  = M_B_CPU1_SB_DQ<14>
  VSS115  = GND
  DQ15_B  = M_B_CPU1_SB_DQ<15>
  VSS116  = GND
  DQ18_B  = M_B_CPU1_SB_DQ<18>
  VSS117  = GND
  DQ19_B  = M_B_CPU1_SB_DQ<19>
  VSS118  = GND
  \dqs7_b_c||tdqs7_b_c\  = M_B_CPU1_SB_DQS_DN<7>
  \dqs7_b_t||tdqs7_b_t\  = M_B_CPU1_SB_DQS_DP<7>
  VSS119  = GND
  DQ22_B  = M_B_CPU1_SB_DQ<22>
  VSS120  = GND
  DQ23_B  = M_B_CPU1_SB_DQ<23>
  VSS121  = GND
  DQ26_B  = M_B_CPU1_SB_DQ<26>
  VSS122  = GND
  DQ27_B  = M_B_CPU1_SB_DQ<27>
  VSS123  = GND
  \dqs8_b_c||tdqs8_b_c\  = M_B_CPU1_SB_DQS_DN<8>
  \dqs8_b_t||tdqs8_b_t\  = M_B_CPU1_SB_DQS_DP<8>
  VSS124  = GND
  DQ30_B  = M_B_CPU1_SB_DQ<30>
  VSS125  = GND
  DQ31_B  = M_B_CPU1_SB_DQ<31>
  VSS126  = GND
  G1  = GND
  G2  = GND
  G3  = GND

(kicad_pcb
	(version 20260206)
	(generator "pcbnew")
	(generator_version "10.0")
	(general
		(thickness 1.6)
		(legacy_teardrops no)
	)
	(paper "A4")
	(title_block
		(title "04192023_DAF0TMB3IC0_F0TG_MB_C_brd_V02_OCP.brd")
		(comment 1 "Grand Teton / footprint 4371 of 8354 (J26), pads 139-184 of 291")
	)
	(layers
		(0 "F.Cu" signal "TOP")
		(4 "In1.Cu" signal "GND")
		(6 "In2.Cu" signal "IN1")
		(8 "In3.Cu" signal "GND1")
		(10 "In4.Cu" signal "IN2")
		(12 "In5.Cu" signal "GND2")
		(14 "In6.Cu" signal "IN3")
		(16 "In7.Cu" signal "GND3")
		(18 "In8.Cu" signal "VCC")
		(20 "In9.Cu" signal "VCC1")
		(22 "In10.Cu" signal "GND4")
		(24 "In11.Cu" signal "IN4")
		(26 "In12.Cu" signal "GND5")
		(28 "In13.Cu" signal "IN5")
		(30 "In14.Cu" signal "GND6")
		(32 "In15.Cu" signal "IN6")
		(34 "In16.Cu" signal "GND7")
		(2 "B.Cu" signal "BOTTOM")
		(9 "F.Adhes" user "F.Adhesive")
		(11 "B.Adhes" user "B.Adhesive")
		(13 "F.Paste" user "Package Geometry/Pastemask Top")
		(15 "B.Paste" user "Package Geometry/Pastemask Bottom")
		(5 "F.SilkS" user "Ref Des/Silkscreen Top")
		(7 "B.SilkS" user "Ref Des/Silkscreen Bottom")
		(1 "F.Mask" user "Board Geometry/Soldermask Top")
		(3 "B.Mask" user "Board Geometry/Soldermask Bottom")
		(17 "Dwgs.User" user "User.Drawings")
		(19 "Cmts.User" user "User.Comments")
		(21 "Eco1.User" user "User.Eco1")
		(23 "Eco2.User" user "User.Eco2")
		(25 "Edge.Cuts" user "Board Geometry/Outline")
		(27 "Margin" user)
		(31 "F.CrtYd" user "Package Geometry/Place Bound Top")
		(29 "B.CrtYd" user "Package Geometry/Place Bound Bottom")
		(35 "F.Fab" user "Ref Des/Assembly Top")
		(33 "B.Fab" user "Ref Des/Assembly Bottom")
	)
	(footprint ""
		(layer "F.Cu")
		(at 49.834038 -255.560322 180)
		(property "Reference" "J26"
			(at -0.703326 -82.357722 0)
			(unlocked yes)
			(layer "F.SilkS")
			(effects
				(font
					(size 0.7874 0.5842)
					(thickness 0.1524)
				)
			)
		)
		(property "Value" ""
			(at 0 0 180)
			(layer "F.Fab")
			(effects
				(font
					(size 1.27 1.27)
				)
			)
		)
		(duplicate_pad_numbers_are_jumpers no)
		(pad "139" smd rect
			(at -2.050034 59.075066 90)
			(size 0.519938 1.4986)
			(layers "F.Cu" "F.Mask" "F.Paste")
			(net "GND")
		)
		(pad "140" smd rect
			(at -2.050034 59.92495 90)
			(size 0.519938 1.4986)
			(layers "F.Cu" "F.Mask" "F.Paste")
			(net "M_B_CPU1_SB_DQ<28>")
		)
		(pad "141" smd rect
			(at -2.050034 60.775088 90)
			(size 0.519938 1.4986)
			(layers "F.Cu" "F.Mask" "F.Paste")
			(net "GND")
		)
		(pad "142" smd rect
			(at -2.050034 61.624972 90)
			(size 0.519938 1.4986)
			(layers "F.Cu" "F.Mask" "F.Paste")
			(net "M_B_CPU1_SB_DQ<29>")
		)
		(pad "143" smd rect
			(at -2.050034 62.47511 90)
			(size 0.519938 1.4986)
			(layers "F.Cu" "F.Mask" "F.Paste")
			(net "GND")
		)
		(pad "144" smd rect
			(at -2.050034 63.324994 90)
			(size 0.519938 1.4986)
			(layers "F.Cu" "F.Mask" "F.Paste")
			(net "Net_2271")
		)
		(pad "145" smd rect
			(at 2.050034 -63.324994 90)
			(size 0.519938 1.4986)
			(layers "F.Cu" "F.Mask" "F.Paste")
			(net "P12V_MEM_CPU1")
		)
		(pad "146" smd rect
			(at 2.050034 -62.47511 90)
			(size 0.519938 1.4986)
			(layers "F.Cu" "F.Mask" "F.Paste")
			(net "P12V_MEM_CPU1")
		)
		(pad "147" smd rect
			(at 2.050034 -61.624972 90)
			(size 0.519938 1.4986)
			(layers "F.Cu" "F.Mask" "F.Paste")
			(net "PWRGD_CHB_CPU1_DIMM")
		)
		(pad "148" smd rect
			(at 2.050034 -60.775088 90)
			(size 0.519938 1.4986)
			(layers "F.Cu" "F.Mask" "F.Paste")
			(net "PD_CHB_CPU1_DIMM_SAA")
		)
		(pad "149" smd rect
			(at 2.050034 -59.92495 90)
			(size 0.519938 1.4986)
			(layers "F.Cu" "F.Mask" "F.Paste")
			(net "Net_2272")
		)
		(pad "150" smd rect
			(at 2.050034 -59.075066 90)
			(size 0.519938 1.4986)
			(layers "F.Cu" "F.Mask" "F.Paste")
			(net "Net_2273")
		)
		(pad "151" smd rect
			(at 2.050034 -58.224928 90)
			(size 0.519938 1.4986)
			(layers "F.Cu" "F.Mask" "F.Paste")
			(net "GND")
		)
		(pad "152" smd rect
			(at 2.050034 -57.375044 90)
			(size 0.519938 1.4986)
			(layers "F.Cu" "F.Mask" "F.Paste")
			(net "M_B_CPU1_SA_DQ<2>")
		)
		(pad "153" smd rect
			(at 2.050034 -56.524906 90)
			(size 0.519938 1.4986)
			(layers "F.Cu" "F.Mask" "F.Paste")
			(net "GND")
		)
		(pad "154" smd rect
			(at 2.050034 -55.675022 90)
			(size 0.519938 1.4986)
			(layers "F.Cu" "F.Mask" "F.Paste")
			(net "M_B_CPU1_SA_DQ<3>")
		)
		(pad "155" smd rect
			(at 2.050034 -54.824884 90)
			(size 0.519938 1.4986)
			(layers "F.Cu" "F.Mask" "F.Paste")
			(net "GND")
		)
		(pad "156" smd rect
			(at 2.050034 -53.975 90)
			(size 0.519938 1.4986)
			(layers "F.Cu" "F.Mask" "F.Paste")
			(net "M_B_CPU1_SA_DQS_DN<5>")
		)
		(pad "157" smd rect
			(at 2.050034 -53.125116 90)
			(size 0.519938 1.4986)
			(layers "F.Cu" "F.Mask" "F.Paste")
			(net "M_B_CPU1_SA_DQS_DP<5>")
		)
		(pad "158" smd rect
			(at 2.050034 -52.274978 90)
			(size 0.519938 1.4986)
			(layers "F.Cu" "F.Mask" "F.Paste")
			(net "GND")
		)
		(pad "159" smd rect
			(at 2.050034 -51.425094 90)
			(size 0.519938 1.4986)
			(layers "F.Cu" "F.Mask" "F.Paste")
			(net "M_B_CPU1_SA_DQ<6>")
		)
		(pad "160" smd rect
			(at 2.050034 -50.574956 90)
			(size 0.519938 1.4986)
			(layers "F.Cu" "F.Mask" "F.Paste")
			(net "GND")
		)
		(pad "161" smd rect
			(at 2.050034 -49.725072 90)
			(size 0.519938 1.4986)
			(layers "F.Cu" "F.Mask" "F.Paste")
			(net "M_B_CPU1_SA_DQ<7>")
		)
		(pad "162" smd rect
			(at 2.050034 -48.874934 90)
			(size 0.519938 1.4986)
			(layers "F.Cu" "F.Mask" "F.Paste")
			(net "GND")
		)
		(pad "163" smd rect
			(at 2.050034 -48.02505 90)
			(size 0.519938 1.4986)
			(layers "F.Cu" "F.Mask" "F.Paste")
			(net "M_B_CPU1_SA_DQ<10>")
		)
		(pad "164" smd rect
			(at 2.050034 -47.174912 90)
			(size 0.519938 1.4986)
			(layers "F.Cu" "F.Mask" "F.Paste")
			(net "GND")
		)
		(pad "165" smd rect
			(at 2.050034 -46.325028 90)
			(size 0.519938 1.4986)
			(layers "F.Cu" "F.Mask" "F.Paste")
			(net "M_B_CPU1_SA_DQ<11>")
		)
		(pad "166" smd rect
			(at 2.050034 -45.47489 90)
			(size 0.519938 1.4986)
			(layers "F.Cu" "F.Mask" "F.Paste")
			(net "GND")
		)
		(pad "167" smd rect
			(at 2.050034 -44.625006 90)
			(size 0.519938 1.4986)
			(layers "F.Cu" "F.Mask" "F.Paste")
			(net "M_B_CPU1_SA_DQS_DN<6>")
		)
		(pad "168" smd rect
			(at 2.050034 -43.775122 90)
			(size 0.519938 1.4986)
			(layers "F.Cu" "F.Mask" "F.Paste")
			(net "M_B_CPU1_SA_DQS_DP<6>")
		)
		(pad "169" smd rect
			(at 2.050034 -42.924984 90)
			(size 0.519938 1.4986)
			(layers "F.Cu" "F.Mask" "F.Paste")
			(net "GND")
		)
		(pad "170" smd rect
			(at 2.050034 -42.0751 90)
			(size 0.519938 1.4986)
			(layers "F.Cu" "F.Mask" "F.Paste")
			(net "M_B_CPU1_SA_DQ<14>")
		)
		(pad "171" smd rect
			(at 2.050034 -41.224962 90)
			(size 0.519938 1.4986)
			(layers "F.Cu" "F.Mask" "F.Paste")
			(net "GND")
		)
		(pad "172" smd rect
			(at 2.050034 -40.375078 90)
			(size 0.519938 1.4986)
			(layers "F.Cu" "F.Mask" "F.Paste")
			(net "M_B_CPU1_SA_DQ<15>")
		)
		(pad "173" smd rect
			(at 2.050034 -39.52494 90)
			(size 0.519938 1.4986)
			(layers "F.Cu" "F.Mask" "F.Paste")
			(net "GND")
		)
		(pad "174" smd rect
			(at 2.050034 -38.675056 90)
			(size 0.519938 1.4986)
			(layers "F.Cu" "F.Mask" "F.Paste")
			(net "M_B_CPU1_SA_DQ<18>")
		)
		(pad "175" smd rect
			(at 2.050034 -37.824918 90)
			(size 0.519938 1.4986)
			(layers "F.Cu" "F.Mask" "F.Paste")
			(net "GND")
		)
		(pad "176" smd rect
			(at 2.050034 -36.975034 90)
			(size 0.519938 1.4986)
			(layers "F.Cu" "F.Mask" "F.Paste")
			(net "M_B_CPU1_SA_DQ<19>")
		)
		(pad "177" smd rect
			(at 2.050034 -36.124896 90)
			(size 0.519938 1.4986)
			(layers "F.Cu" "F.Mask" "F.Paste")
			(net "GND")
		)
		(pad "178" smd rect
			(at 2.050034 -35.275012 90)
			(size 0.519938 1.4986)
			(layers "F.Cu" "F.Mask" "F.Paste")
			(net "M_B_CPU1_SA_DQS_DN<7>")
		)
		(pad "179" smd rect
			(at 2.050034 -34.425128 90)
			(size 0.519938 1.4986)
			(layers "F.Cu" "F.Mask" "F.Paste")
			(net "M_B_CPU1_SA_DQS_DP<7>")
		)
		(pad "180" smd rect
			(at 2.050034 -33.57499 90)
			(size 0.519938 1.4986)
			(layers "F.Cu" "F.Mask" "F.Paste")
			(net "GND")
		)
		(pad "181" smd rect
			(at 2.050034 -32.725106 90)
			(size 0.519938 1.4986)
			(layers "F.Cu" "F.Mask" "F.Paste")
			(net "M_B_CPU1_SA_DQ<22>")
		)
		(pad "182" smd rect
			(at 2.050034 -31.874968 90)
			(size 0.519938 1.4986)
			(layers "F.Cu" "F.Mask" "F.Paste")
			(net "GND")
		)
		(pad "183" smd rect
			(at 2.050034 -31.025084 90)
			(size 0.519938 1.4986)
			(layers "F.Cu" "F.Mask" "F.Paste")
			(net "M_B_CPU1_SA_DQ<23>")
		)
		(pad "184" smd rect
			(at 2.050034 -30.174946 90)
			(size 0.519938 1.4986)
			(layers "F.Cu" "F.Mask" "F.Paste")
			(net "GND")
		)
	)
)
